#ISCELL
  mstr_misc dns *
  *
#ISCELL
  pure_quanta quanta_title_block_c *
  *
#ISCELL
  pure_quanta_power cad_note *
  *
#ISCELL
  pure_quanta_power universal_gnd *
  page369_i1
#CELL
  pure_quanta q_res *
  page369_i10
#ISCELL
  standard offpage *
  page369_i100
#ISCELL
  standard offpage *
  page369_i101
#ISCELL
  standard offpage *
  page369_i102
#ISCELL
  standard offpage *
  page369_i103
#ISCELL
  standard offpage *
  page369_i104
#ISCELL
  standard offpage *
  page369_i105
#ISCELL
  standard offpage *
  page369_i106
#CELL
  pure_quanta q_res *
  page369_i107
#CELL
  pure_quanta q_res *
  page369_i108
#CELL
  pure_quanta q_res *
  page369_i109
#ISCELL
  pure_quanta_power universal_gnd *
  page369_i11
#CELL
  pure_quanta q_res *
  page369_i110
#ISCELL
  pure_quanta_power universal_gnd *
  page369_i111
#CELL
  pure_quanta q_cap *
  page369_i112
#ISCELL
  pure_quanta_power universal_gnd *
  page369_i113
#CELL
  pure_quanta q_cap *
  page369_i114
#CELL
  pure_quanta q_res *
  page369_i115
#ISCELL
  standard offpage *
  page369_i116
#ISCELL
  standard offpage *
  page369_i117
#ISCELL
  pure_quanta_power universal_gnd *
  page369_i118
#CELL
  pure_quanta q_cap *
  page369_i119
#ISCELL
  pure_quanta_power universal_gnd *
  page369_i12
#ISCELL
  pure_quanta_power universal_gnd *
  page369_i120
#CELL
  pure_quanta q_cap *
  page369_i121
#ISCELL
  standard offpage *
  page369_i122
#ISCELL
  standard offpage *
  page369_i123
#ISCELL
  standard offpage *
  page369_i124
#ISCELL
  pure_quanta_power universal_gnd *
  page369_i125
#ISCELL
  standard offpage *
  page369_i126
#ISCELL
  standard offpage *
  page369_i127
#ISCELL
  standard offpage *
  page369_i128
#ISCELL
  standard offpage *
  page369_i129
#ISCELL
  pure_quanta_power universal_gnd *
  page369_i13
#CELL
  pure_quanta q_res *
  page369_i130
#CELL
  pure_quanta q_res *
  page369_i131
#ISCELL
  standard offpage *
  page369_i132
#ISCELL
  standard offpage *
  page369_i133
#ISCELL
  standard offpage *
  page369_i134
#ISCELL
  standard offpage *
  page369_i135
#ISCELL
  standard offpage *
  page369_i136
#ISCELL
  standard offpage *
  page369_i137
#ISCELL
  standard offpage *
  page369_i138
#ISCELL
  standard offpage *
  page369_i139
#CELL
  pure_quanta q_res *
  page369_i14
#ISCELL
  standard offpage *
  page369_i140
#ISCELL
  standard offpage *
  page369_i141
#CELL
  pure_quanta adc128d818cimtxnopb *
  page369_i142
#ISCELL
  standard offpage *
  page369_i143
#ISCELL
  standard offpage *
  page369_i144
#ISCELL
  pure_quanta_power universal_gnd *
  page369_i145
#CELL
  pure_quanta q_res *
  page369_i146
#CELL
  pure_quanta q_res *
  page369_i147
#ISCELL
  pure_quanta_power universal_gnd *
  page369_i148
#CELL
  pure_quanta q_res *
  page369_i149
#CELL
  pure_quanta q_res *
  page369_i15
#CELL
  pure_quanta q_res *
  page369_i150
#ISCELL
  pure_quanta_power universal_gnd *
  page369_i151
#ISCELL
  standard offpage *
  page369_i152
#ISCELL
  standard offpage *
  page369_i153
#ISCELL
  standard offpage *
  page369_i154
#ISCELL
  standard offpage *
  page369_i155
#ISCELL
  standard offpage *
  page369_i156
#ISCELL
  standard offpage *
  page369_i157
#ISCELL
  standard offpage *
  page369_i158
#ISCELL
  standard offpage *
  page369_i159
#CELL
  pure_quanta q_res *
  page369_i16
#CELL
  pure_quanta q_res *
  page369_i160
#ISCELL
  pure_quanta_power universal_gnd *
  page369_i161
#CELL
  pure_quanta q_cap *
  page369_i162
#ISCELL
  pure_quanta_power universal_gnd *
  page369_i163
#ISCELL
  standard offpage *
  page369_i164
#ISCELL
  standard offpage *
  page369_i165
#CELL
  pure_quanta q_cap *
  page369_i166
#CELL
  pure_quanta q_inductor *
  page369_i167
#ISCELL
  pure_quanta_power universal_power *
  page369_i168
#CELL
  pure_quanta max11617eeet *
  page369_i169
#CELL
  pure_quanta q_cap *
  page369_i17
#CELL
  pure_quanta q_res *
  page369_i170
#CELL
  pure_quanta q_res *
  page369_i18
#ISCELL
  pure_quanta_power universal_power *
  page369_i19
#ISCELL
  standard offpage *
  page369_i2
#CELL
  pure_quanta q_res *
  page369_i20
#CELL
  pure_quanta q_res *
  page369_i21
#CELL
  pure_quanta q_res *
  page369_i22
#CELL
  pure_quanta q_res *
  page369_i23
#ISCELL
  pure_quanta_power universal_gnd *
  page369_i24
#ISCELL
  pure_quanta_power universal_power *
  page369_i25
#CELL
  pure_quanta q_res *
  page369_i26
#CELL
  pure_quanta q_res *
  page369_i27
#CELL
  pure_quanta q_res *
  page369_i28
#ISCELL
  pure_quanta_power universal_power *
  page369_i29
#ISCELL
  pure_quanta_power universal_gnd *
  page369_i3
#CELL
  pure_quanta q_res *
  page369_i30
#ISCELL
  pure_quanta_power universal_gnd *
  page369_i31
#CELL
  pure_quanta q_cap *
  page369_i32
#ISCELL
  pure_quanta_power universal_gnd *
  page369_i33
#CELL
  pure_quanta q_cap *
  page369_i34
#ISCELL
  pure_quanta_power universal_gnd *
  page369_i35
#CELL
  pure_quanta q_cap *
  page369_i36
#ISCELL
  pure_quanta_power universal_gnd *
  page369_i37
#CELL
  pure_quanta q_res *
  page369_i38
#ISCELL
  pure_quanta_power universal_gnd *
  page369_i39
#CELL
  pure_quanta q_res *
  page369_i40
#CELL
  pure_quanta q_res *
  page369_i41
#CELL
  pure_quanta q_res *
  page369_i42
#ISCELL
  pure_quanta_power universal_gnd *
  page369_i43
#CELL
  pure_quanta q_cap *
  page369_i44
#ISCELL
  pure_quanta_power universal_gnd *
  page369_i45
#CELL
  pure_quanta q_cap *
  page369_i46
#ISCELL
  pure_quanta_power universal_gnd *
  page369_i47
#ISCELL
  standard offpage *
  page369_i48
#ISCELL
  standard offpage *
  page369_i49
#ISCELL
  pure_quanta_power universal_power *
  page369_i5
#ISCELL
  standard offpage *
  page369_i50
#ISCELL
  standard offpage *
  page369_i51
#CELL
  pure_quanta q_cap *
  page369_i52
#ISCELL
  standard offpage *
  page369_i53
#ISCELL
  standard offpage *
  page369_i54
#CELL
  pure_quanta q_cap *
  page369_i55
#ISCELL
  pure_quanta_power universal_gnd *
  page369_i56
#ISCELL
  standard offpage *
  page369_i57
#ISCELL
  standard offpage *
  page369_i58
#ISCELL
  standard offpage *
  page369_i59
#CELL
  pure_quanta q_res *
  page369_i6
#ISCELL
  standard offpage *
  page369_i60
#ISCELL
  standard offpage *
  page369_i61
#ISCELL
  standard offpage *
  page369_i62
#ISCELL
  standard offpage *
  page369_i63
#ISCELL
  standard offpage *
  page369_i64
#ISCELL
  standard offpage *
  page369_i65
#CELL
  pure_quanta q_res *
  page369_i66
#ISCELL
  pure_quanta_power universal_power *
  page369_i67
#CELL
  pure_quanta q_res *
  page369_i68
#CELL
  pure_quanta q_inductor *
  page369_i69
#CELL
  pure_quanta q_res *
  page369_i7
#ISCELL
  pure_quanta_power universal_gnd *
  page369_i70
#CELL
  pure_quanta q_cap *
  page369_i71
#CELL
  pure_quanta q_cap *
  page369_i72
#CELL
  pure_quanta q_res *
  page369_i73
#CELL
  pure_quanta q_res *
  page369_i74
#ISCELL
  pure_quanta_power universal_gnd *
  page369_i75
#CELL
  pure_quanta q_cap *
  page369_i76
#ISCELL
  pure_quanta_power universal_gnd *
  page369_i77
#CELL
  pure_quanta q_cap *
  page369_i78
#CELL
  pure_quanta q_res *
  page369_i79
#CELL
  pure_quanta q_res *
  page369_i8
#CELL
  pure_quanta q_res *
  page369_i80
#CELL
  pure_quanta q_res *
  page369_i81
#CELL
  pure_quanta q_res *
  page369_i82
#CELL
  pure_quanta q_res *
  page369_i83
#CELL
  pure_quanta q_cap *
  page369_i84
#ISCELL
  pure_quanta_power universal_gnd *
  page369_i85
#ISCELL
  pure_quanta_power universal_gnd *
  page369_i86
#CELL
  pure_quanta q_cap *
  page369_i87
#ISCELL
  pure_quanta_power universal_power *
  page369_i88
#ISCELL
  standard offpage *
  page369_i89
#CELL
  pure_quanta q_res *
  page369_i9
#ISCELL
  standard offpage *
  page369_i90
#ISCELL
  standard offpage *
  page369_i91
#ISCELL
  standard offpage *
  page369_i92
#ISCELL
  standard offpage *
  page369_i93
#ISCELL
  standard offpage *
  page369_i94
#ISCELL
  standard offpage *
  page369_i95
#ISCELL
  pure_quanta_power universal_gnd *
  page369_i96
#ISCELL
  pure_quanta_power universal_gnd *
  page369_i97
#CELL
  pure_quanta q_cap *
  page369_i98
#CELL
  pure_quanta q_cap *
  page369_i99
